(kicad_pcb
	(version 20260206)
	(generator "pcbnew")
	(generator_version "10.0")
	(general
		(thickness 1.6)
		(legacy_teardrops no)
	)
	(paper "A4")
	(title_block
		(title "04192023_DAF0TMB3IC0_F0TG_MB_C_brd_V02_OCP.brd")
		(comment 1 "Grand Teton / footprints 8254-8260 of 8354")
	)
	(layers
		(0 "F.Cu" signal "TOP")
		(4 "In1.Cu" signal "GND")
		(6 "In2.Cu" signal "IN1")
		(8 "In3.Cu" signal "GND1")
		(10 "In4.Cu" signal "IN2")
		(12 "In5.Cu" signal "GND2")
		(14 "In6.Cu" signal "IN3")
		(16 "In7.Cu" signal "GND3")
		(18 "In8.Cu" signal "VCC")
		(20 "In9.Cu" signal "VCC1")
		(22 "In10.Cu" signal "GND4")
		(24 "In11.Cu" signal "IN4")
		(26 "In12.Cu" signal "GND5")
		(28 "In13.Cu" signal "IN5")
		(30 "In14.Cu" signal "GND6")
		(32 "In15.Cu" signal "IN6")
		(34 "In16.Cu" signal "GND7")
		(2 "B.Cu" signal "BOTTOM")
		(9 "F.Adhes" user "F.Adhesive")
		(11 "B.Adhes" user "B.Adhesive")
		(13 "F.Paste" user "Package Geometry/Pastemask Top")
		(15 "B.Paste" user "Package Geometry/Pastemask Bottom")
		(5 "F.SilkS" user "Ref Des/Silkscreen Top")
		(7 "B.SilkS" user "Ref Des/Silkscreen Bottom")
		(1 "F.Mask" user "Board Geometry/Soldermask Top")
		(3 "B.Mask" user "Board Geometry/Soldermask Bottom")
		(17 "Dwgs.User" user "User.Drawings")
		(19 "Cmts.User" user "User.Comments")
		(21 "Eco1.User" user "User.Eco1")
		(23 "Eco2.User" user "User.Eco2")
		(25 "Edge.Cuts" user "Board Geometry/Outline")
		(27 "Margin" user)
		(31 "F.CrtYd" user "Package Geometry/Place Bound Top")
		(29 "B.CrtYd" user "Package Geometry/Place Bound Bottom")
		(35 "F.Fab" user "Ref Des/Assembly Top")
		(33 "B.Fab" user "Ref Des/Assembly Bottom")
	)
	(footprint ""
		(layer "B.Cu")
		(at 22.479 -359.918 180)
		(property "Reference" "R8225"
			(at 0 0 0)
			(layer "B.SilkS")
			(hide yes)
			(effects
				(font
					(size 1.27 1.27)
				)
				(justify mirror)
			)
		)
		(property "Value" ""
			(at 0 0 0)
			(layer "B.Fab")
			(effects
				(font
					(size 1.27 1.27)
				)
				(justify mirror)
			)
		)
		(duplicate_pad_numbers_are_jumpers no)
		(fp_line
			(start 0.7874 0.4064)
			(end 0.7874 -0.4064)
			(stroke
				(width 0.1524)
				(type default)
			)
			(layer "B.SilkS")
		)
		(fp_line
			(start 0.7874 -0.4064)
			(end -0.7874 -0.4064)
			(stroke
				(width 0.1524)
				(type default)
			)
			(layer "B.SilkS")
		)
		(fp_line
			(start -0.7874 0.4064)
			(end 0.7874 0.4064)
			(stroke
				(width 0.1524)
				(type default)
			)
			(layer "B.SilkS")
		)
		(fp_line
			(start -0.7874 -0.4064)
			(end -0.7874 0.4064)
			(stroke
				(width 0.1524)
				(type default)
			)
			(layer "B.SilkS")
		)
		(fp_line
			(start 0.67945 0.3048)
			(end 0.67945 -0.305054)
			(stroke
				(width 0.1)
				(type default)
			)
			(layer "B.Fab")
		)
		(fp_line
			(start 0.67945 -0.305054)
			(end 0.12065 -0.305054)
			(stroke
				(width 0.1)
				(type default)
			)
			(layer "B.Fab")
		)
		(fp_line
			(start 0.12065 0.3048)
			(end 0.67945 0.3048)
			(stroke
				(width 0.1)
				(type default)
			)
			(layer "B.Fab")
		)
		(fp_line
			(start 0.12065 0.2794)
			(end 0.12065 0.3048)
			(stroke
				(width 0.1)
				(type default)
			)
			(layer "B.Fab")
		)
		(fp_line
			(start 0.12065 -0.2794)
			(end -0.12065 -0.2794)
			(stroke
				(width 0.1)
				(type default)
			)
			(layer "B.Fab")
		)
		(fp_line
			(start 0.12065 -0.305054)
			(end 0.12065 -0.2794)
			(stroke
				(width 0.1)
				(type default)
			)
			(layer "B.Fab")
		)
		(fp_line
			(start -0.120396 0.3048)
			(end -0.120396 0.2794)
			(stroke
				(width 0.1)
				(type default)
			)
			(layer "B.Fab")
		)
		(fp_line
			(start -0.120396 0.2794)
			(end 0.12065 0.2794)
			(stroke
				(width 0.1)
				(type default)
			)
			(layer "B.Fab")
		)
		(fp_line
			(start -0.12065 -0.2794)
			(end -0.12065 -0.3048)
			(stroke
				(width 0.1)
				(type default)
			)
			(layer "B.Fab")
		)
		(fp_line
			(start -0.12065 -0.3048)
			(end -0.67945 -0.3048)
			(stroke
				(width 0.1)
				(type default)
			)
			(layer "B.Fab")
		)
		(fp_line
			(start -0.67945 0.3048)
			(end -0.120396 0.3048)
			(stroke
				(width 0.1)
				(type default)
			)
			(layer "B.Fab")
		)
		(fp_line
			(start -0.67945 -0.3048)
			(end -0.67945 0.3048)
			(stroke
				(width 0.1)
				(type default)
			)
			(layer "B.Fab")
		)
		(pad "1" smd circle
			(at 0.40005 0)
			(size 0 0)
			(layers "B.Cu" "B.Mask" "B.Paste")
			(net "PVDD18_S5_P1")
		)
		(pad "2" smd circle
			(at -0.40005 0)
			(size 0 0)
			(layers "B.Cu" "B.Mask" "B.Paste")
			(net "SVID_PVDDCR_CPU1_P1_SVC_R")
		)
	)
	(footprint ""
		(layer "B.Cu")
		(at 115.03406 -28.449778 -90)
		(property "Reference" "C6108"
			(at 0 0 90)
			(layer "B.SilkS")
			(hide yes)
			(effects
				(font
					(size 1.27 1.27)
				)
				(justify mirror)
			)
		)
		(property "Value" ""
			(at 0 0 90)
			(layer "B.Fab")
			(effects
				(font
					(size 1.27 1.27)
				)
				(justify mirror)
			)
		)
		(duplicate_pad_numbers_are_jumpers no)
		(fp_line
			(start -0.7874 0.4064)
			(end 0.7874 0.4064)
			(stroke
				(width 0.1524)
				(type default)
			)
			(layer "B.SilkS")
		)
		(fp_line
			(start 0.7874 0.4064)
			(end 0.7874 -0.4064)
			(stroke
				(width 0.1524)
				(type default)
			)
			(layer "B.SilkS")
		)
		(fp_line
			(start -0.7874 -0.4064)
			(end -0.7874 0.4064)
			(stroke
				(width 0.1524)
				(type default)
			)
			(layer "B.SilkS")
		)
		(fp_line
			(start 0.7874 -0.4064)
			(end -0.7874 -0.4064)
			(stroke
				(width 0.1524)
				(type default)
			)
			(layer "B.SilkS")
		)
		(fp_line
			(start -0.67945 0.3048)
			(end -0.120396 0.3048)
			(stroke
				(width 0.1)
				(type default)
			)
			(layer "B.Fab")
		)
		(fp_line
			(start -0.120396 0.3048)
			(end -0.120396 0.2794)
			(stroke
				(width 0.1)
				(type default)
			)
			(layer "B.Fab")
		)
		(fp_line
			(start 0.12065 0.3048)
			(end 0.67945 0.3048)
			(stroke
				(width 0.1)
				(type default)
			)
			(layer "B.Fab")
		)
		(fp_line
			(start 0.67945 0.3048)
			(end 0.67945 -0.305054)
			(stroke
				(width 0.1)
				(type default)
			)
			(layer "B.Fab")
		)
		(fp_line
			(start -0.120396 0.2794)
			(end 0.12065 0.2794)
			(stroke
				(width 0.1)
				(type default)
			)
			(layer "B.Fab")
		)
		(fp_line
			(start 0.12065 0.2794)
			(end 0.12065 0.3048)
			(stroke
				(width 0.1)
				(type default)
			)
			(layer "B.Fab")
		)
		(fp_line
			(start -0.12065 -0.2794)
			(end -0.12065 -0.3048)
			(stroke
				(width 0.1)
				(type default)
			)
			(layer "B.Fab")
		)
		(fp_line
			(start 0.12065 -0.2794)
			(end -0.12065 -0.2794)
			(stroke
				(width 0.1)
				(type default)
			)
			(layer "B.Fab")
		)
		(fp_line
			(start -0.67945 -0.3048)
			(end -0.67945 0.3048)
			(stroke
				(width 0.1)
				(type default)
			)
			(layer "B.Fab")
		)
		(fp_line
			(start -0.12065 -0.3048)
			(end -0.67945 -0.3048)
			(stroke
				(width 0.1)
				(type default)
			)
			(layer "B.Fab")
		)
		(fp_line
			(start 0.12065 -0.305054)
			(end 0.12065 -0.2794)
			(stroke
				(width 0.1)
				(type default)
			)
			(layer "B.Fab")
		)
		(fp_line
			(start 0.67945 -0.305054)
			(end 0.12065 -0.305054)
			(stroke
				(width 0.1)
				(type default)
			)
			(layer "B.Fab")
		)
		(pad "1" smd circle
			(at 0.40005 0 90)
			(size 0 0)
			(layers "B.Cu" "B.Mask" "B.Paste")
			(net "P1V2_CPU0_USB2_DVDD12")
		)
		(pad "2" smd circle
			(at -0.40005 0 90)
			(size 0 0)
			(layers "B.Cu" "B.Mask" "B.Paste")
			(net "GND")
		)
	)
	(footprint ""
		(layer "B.Cu")
		(at 164.33546 -190.821564 180)
		(property "Reference" "R1184"
			(at 0 0 0)
			(layer "B.SilkS")
			(hide yes)
			(effects
				(font
					(size 1.27 1.27)
				)
				(justify mirror)
			)
		)
		(property "Value" ""
			(at 0 0 0)
			(layer "B.Fab")
			(effects
				(font
					(size 1.27 1.27)
				)
				(justify mirror)
			)
		)
		(duplicate_pad_numbers_are_jumpers no)
		(fp_line
			(start 0.7874 0.4064)
			(end 0.7874 -0.4064)
			(stroke
				(width 0.1524)
				(type default)
			)
			(layer "B.SilkS")
		)
		(fp_line
			(start 0.7874 -0.4064)
			(end -0.7874 -0.4064)
			(stroke
				(width 0.1524)
				(type default)
			)
			(layer "B.SilkS")
		)
		(fp_line
			(start -0.7874 0.4064)
			(end 0.7874 0.4064)
			(stroke
				(width 0.1524)
				(type default)
			)
			(layer "B.SilkS")
		)
		(fp_line
			(start -0.7874 -0.4064)
			(end -0.7874 0.4064)
			(stroke
				(width 0.1524)
				(type default)
			)
			(layer "B.SilkS")
		)
		(fp_line
			(start 0.67945 0.3048)
			(end 0.67945 -0.305054)
			(stroke
				(width 0.1)
				(type default)
			)
			(layer "B.Fab")
		)
		(fp_line
			(start 0.67945 -0.305054)
			(end 0.12065 -0.305054)
			(stroke
				(width 0.1)
				(type default)
			)
			(layer "B.Fab")
		)
		(fp_line
			(start 0.12065 0.3048)
			(end 0.67945 0.3048)
			(stroke
				(width 0.1)
				(type default)
			)
			(layer "B.Fab")
		)
		(fp_line
			(start 0.12065 0.2794)
			(end 0.12065 0.3048)
			(stroke
				(width 0.1)
				(type default)
			)
			(layer "B.Fab")
		)
		(fp_line
			(start 0.12065 -0.2794)
			(end -0.12065 -0.2794)
			(stroke
				(width 0.1)
				(type default)
			)
			(layer "B.Fab")
		)
		(fp_line
			(start 0.12065 -0.305054)
			(end 0.12065 -0.2794)
			(stroke
				(width 0.1)
				(type default)
			)
			(layer "B.Fab")
		)
		(fp_line
			(start -0.120396 0.3048)
			(end -0.120396 0.2794)
			(stroke
				(width 0.1)
				(type default)
			)
			(layer "B.Fab")
		)
		(fp_line
			(start -0.120396 0.2794)
			(end 0.12065 0.2794)
			(stroke
				(width 0.1)
				(type default)
			)
			(layer "B.Fab")
		)
		(fp_line
			(start -0.12065 -0.2794)
			(end -0.12065 -0.3048)
			(stroke
				(width 0.1)
				(type default)
			)
			(layer "B.Fab")
		)
		(fp_line
			(start -0.12065 -0.3048)
			(end -0.67945 -0.3048)
			(stroke
				(width 0.1)
				(type default)
			)
			(layer "B.Fab")
		)
		(fp_line
			(start -0.67945 0.3048)
			(end -0.120396 0.3048)
			(stroke
				(width 0.1)
				(type default)
			)
			(layer "B.Fab")
		)
		(fp_line
			(start -0.67945 -0.3048)
			(end -0.67945 0.3048)
			(stroke
				(width 0.1)
				(type default)
			)
			(layer "B.Fab")
		)
		(pad "1" smd circle
			(at 0.40005 0)
			(size 0 0)
			(layers "B.Cu" "B.Mask" "B.Paste")
			(net "PWRGD_CHG_CPU1_DIMM0")
		)
		(pad "2" smd circle
			(at -0.40005 0)
			(size 0 0)
			(layers "B.Cu" "B.Mask" "B.Paste")
			(net "PWRGD_CHGL_CPU1")
		)
	)
	(footprint ""
		(layer "B.Cu")
		(at 137.851642 -9.036304 -90)
		(property "Reference" "R6035"
			(at 0 0 90)
			(layer "B.SilkS")
			(hide yes)
			(effects
				(font
					(size 1.27 1.27)
				)
				(justify mirror)
			)
		)
		(property "Value" ""
			(at 0 0 90)
			(layer "B.Fab")
			(effects
				(font
					(size 1.27 1.27)
				)
				(justify mirror)
			)
		)
		(duplicate_pad_numbers_are_jumpers no)
		(fp_line
			(start -0.7874 0.4064)
			(end 0.7874 0.4064)
			(stroke
				(width 0.1524)
				(type default)
			)
			(layer "B.SilkS")
		)
		(fp_line
			(start 0.7874 0.4064)
			(end 0.7874 -0.4064)
			(stroke
				(width 0.1524)
				(type default)
			)
			(layer "B.SilkS")
		)
		(fp_line
			(start -0.7874 -0.4064)
			(end -0.7874 0.4064)
			(stroke
				(width 0.1524)
				(type default)
			)
			(layer "B.SilkS")
		)
		(fp_line
			(start 0.7874 -0.4064)
			(end -0.7874 -0.4064)
			(stroke
				(width 0.1524)
				(type default)
			)
			(layer "B.SilkS")
		)
		(fp_line
			(start -0.67945 0.3048)
			(end -0.120396 0.3048)
			(stroke
				(width 0.1)
				(type default)
			)
			(layer "B.Fab")
		)
		(fp_line
			(start -0.120396 0.3048)
			(end -0.120396 0.2794)
			(stroke
				(width 0.1)
				(type default)
			)
			(layer "B.Fab")
		)
		(fp_line
			(start 0.12065 0.3048)
			(end 0.67945 0.3048)
			(stroke
				(width 0.1)
				(type default)
			)
			(layer "B.Fab")
		)
		(fp_line
			(start 0.67945 0.3048)
			(end 0.67945 -0.305054)
			(stroke
				(width 0.1)
				(type default)
			)
			(layer "B.Fab")
		)
		(fp_line
			(start -0.120396 0.2794)
			(end 0.12065 0.2794)
			(stroke
				(width 0.1)
				(type default)
			)
			(layer "B.Fab")
		)
		(fp_line
			(start 0.12065 0.2794)
			(end 0.12065 0.3048)
			(stroke
				(width 0.1)
				(type default)
			)
			(layer "B.Fab")
		)
		(fp_line
			(start -0.12065 -0.2794)
			(end -0.12065 -0.3048)
			(stroke
				(width 0.1)
				(type default)
			)
			(layer "B.Fab")
		)
		(fp_line
			(start 0.12065 -0.2794)
			(end -0.12065 -0.2794)
			(stroke
				(width 0.1)
				(type default)
			)
			(layer "B.Fab")
		)
		(fp_line
			(start -0.67945 -0.3048)
			(end -0.67945 0.3048)
			(stroke
				(width 0.1)
				(type default)
			)
			(layer "B.Fab")
		)
		(fp_line
			(start -0.12065 -0.3048)
			(end -0.67945 -0.3048)
			(stroke
				(width 0.1)
				(type default)
			)
			(layer "B.Fab")
		)
		(fp_line
			(start 0.12065 -0.305054)
			(end 0.12065 -0.2794)
			(stroke
				(width 0.1)
				(type default)
			)
			(layer "B.Fab")
		)
		(fp_line
			(start 0.67945 -0.305054)
			(end 0.12065 -0.305054)
			(stroke
				(width 0.1)
				(type default)
			)
			(layer "B.Fab")
		)
		(pad "1" smd circle
			(at 0.40005 0 90)
			(size 0 0)
			(layers "B.Cu" "B.Mask" "B.Paste")
			(net "SCM_ROT_CPU_RST_R_N")
		)
		(pad "2" smd circle
			(at -0.40005 0 90)
			(size 0 0)
			(layers "B.Cu" "B.Mask" "B.Paste")
			(net "GND")
		)
	)
	(footprint ""
		(layer "B.Cu")
		(at 117.895624 -255.555242)
		(property "Reference" "C2424"
			(at 0 0 0)
			(layer "B.SilkS")
			(hide yes)
			(effects
				(font
					(size 1.27 1.27)
				)
				(justify mirror)
			)
		)
		(property "Value" ""
			(at 0 0 0)
			(layer "B.Fab")
			(effects
				(font
					(size 1.27 1.27)
				)
				(justify mirror)
			)
		)
		(duplicate_pad_numbers_are_jumpers no)
		(fp_line
			(start -0.7874 -0.4064)
			(end -0.7874 0.4064)
			(stroke
				(width 0.1524)
				(type default)
			)
			(layer "B.SilkS")
		)
		(fp_line
			(start -0.7874 0.4064)
			(end 0.7874 0.4064)
			(stroke
				(width 0.1524)
				(type default)
			)
			(layer "B.SilkS")
		)
		(fp_line
			(start 0.7874 -0.4064)
			(end -0.7874 -0.4064)
			(stroke
				(width 0.1524)
				(type default)
			)
			(layer "B.SilkS")
		)
		(fp_line
			(start 0.7874 0.4064)
			(end 0.7874 -0.4064)
			(stroke
				(width 0.1524)
				(type default)
			)
			(layer "B.SilkS")
		)
		(fp_line
			(start -0.67945 -0.3048)
			(end -0.67945 0.3048)
			(stroke
				(width 0.1)
				(type default)
			)
			(layer "B.Fab")
		)
		(fp_line
			(start -0.67945 0.3048)
			(end -0.120396 0.3048)
			(stroke
				(width 0.1)
				(type default)
			)
			(layer "B.Fab")
		)
		(fp_line
			(start -0.12065 -0.3048)
			(end -0.67945 -0.3048)
			(stroke
				(width 0.1)
				(type default)
			)
			(layer "B.Fab")
		)
		(fp_line
			(start -0.12065 -0.2794)
			(end -0.12065 -0.3048)
			(stroke
				(width 0.1)
				(type default)
			)
			(layer "B.Fab")
		)
		(fp_line
			(start -0.120396 0.2794)
			(end 0.12065 0.2794)
			(stroke
				(width 0.1)
				(type default)
			)
			(layer "B.Fab")
		)
		(fp_line
			(start -0.120396 0.3048)
			(end -0.120396 0.2794)
			(stroke
				(width 0.1)
				(type default)
			)
			(layer "B.Fab")
		)
		(fp_line
			(start 0.12065 -0.305054)
			(end 0.12065 -0.2794)
			(stroke
				(width 0.1)
				(type default)
			)
			(layer "B.Fab")
		)
		(fp_line
			(start 0.12065 -0.2794)
			(end -0.12065 -0.2794)
			(stroke
				(width 0.1)
				(type default)
			)
			(layer "B.Fab")
		)
		(fp_line
			(start 0.12065 0.2794)
			(end 0.12065 0.3048)
			(stroke
				(width 0.1)
				(type default)
			)
			(layer "B.Fab")
		)
		(fp_line
			(start 0.12065 0.3048)
			(end 0.67945 0.3048)
			(stroke
				(width 0.1)
				(type default)
			)
			(layer "B.Fab")
		)
		(fp_line
			(start 0.67945 -0.305054)
			(end 0.12065 -0.305054)
			(stroke
				(width 0.1)
				(type default)
			)
			(layer "B.Fab")
		)
		(fp_line
			(start 0.67945 0.3048)
			(end 0.67945 -0.305054)
			(stroke
				(width 0.1)
				(type default)
			)
			(layer "B.Fab")
		)
		(pad "1" smd circle
			(at 0.40005 0 180)
			(size 0 0)
			(layers "B.Cu" "B.Mask" "B.Paste")
			(net "PVDDCR_SOC_P1")
		)
		(pad "2" smd circle
			(at -0.40005 0 180)
			(size 0 0)
			(layers "B.Cu" "B.Mask" "B.Paste")
			(net "GND")
		)
	)
	(footprint ""
		(layer "B.Cu")
		(at 163.5252 -424.60037 -90)
		(property "Reference" "R1511"
			(at 0 0 90)
			(layer "B.SilkS")
			(hide yes)
			(effects
				(font
					(size 1.27 1.27)
				)
				(justify mirror)
			)
		)
		(property "Value" ""
			(at 0 0 90)
			(layer "B.Fab")
			(effects
				(font
					(size 1.27 1.27)
				)
				(justify mirror)
			)
		)
		(duplicate_pad_numbers_are_jumpers no)
		(fp_line
			(start -0.32512 0.175006)
			(end 0.32512 0.175006)
			(stroke
				(width 0.1)
				(type default)
			)
			(layer "B.Fab")
		)
		(fp_line
			(start 0.32512 0.175006)
			(end 0.32512 -0.175006)
			(stroke
				(width 0.1)
				(type default)
			)
			(layer "B.Fab")
		)
		(fp_line
			(start -0.32512 -0.175006)
			(end -0.32512 0.175006)
			(stroke
				(width 0.1)
				(type default)
			)
			(layer "B.Fab")
		)
		(fp_line
			(start 0.32512 -0.175006)
			(end -0.32512 -0.175006)
			(stroke
				(width 0.1)
				(type default)
			)
			(layer "B.Fab")
		)
		(pad "1" smd rect
			(at 0.2667 0 90)
			(size 0.3048 0.381)
			(layers "B.Cu" "B.Mask" "B.Paste")
			(net "P1V8_CPU1_RT_1D")
		)
		(pad "2" smd rect
			(at -0.2667 0 270)
			(size 0.3048 0.381)
			(layers "B.Cu" "B.Mask" "B.Paste")
			(net "JTAG_TMS_RT_CPU1_P3")
		)
	)
	(footprint ""
		(layer "B.Cu")
		(at 352.596958 -250.89231 180)
		(property "Reference" "C2165"
			(at 0 0 0)
			(layer "B.SilkS")
			(hide yes)
			(effects
				(font
					(size 1.27 1.27)
				)
				(justify mirror)
			)
		)
		(property "Value" ""
			(at 0 0 0)
			(layer "B.Fab")
			(effects
				(font
					(size 1.27 1.27)
				)
				(justify mirror)
			)
		)
		(duplicate_pad_numbers_are_jumpers no)
		(fp_line
			(start 0.7874 0.4064)
			(end 0.7874 -0.4064)
			(stroke
				(width 0.1524)
				(type default)
			)
			(layer "B.SilkS")
		)
		(fp_line
			(start 0.7874 -0.4064)
			(end -0.7874 -0.4064)
			(stroke
				(width 0.1524)
				(type default)
			)
			(layer "B.SilkS")
		)
		(fp_line
			(start -0.7874 0.4064)
			(end 0.7874 0.4064)
			(stroke
				(width 0.1524)
				(type default)
			)
			(layer "B.SilkS")
		)
		(fp_line
			(start -0.7874 -0.4064)
			(end -0.7874 0.4064)
			(stroke
				(width 0.1524)
				(type default)
			)
			(layer "B.SilkS")
		)
		(fp_line
			(start 0.67945 0.3048)
			(end 0.67945 -0.305054)
			(stroke
				(width 0.1)
				(type default)
			)
			(layer "B.Fab")
		)
		(fp_line
			(start 0.67945 -0.305054)
			(end 0.12065 -0.305054)
			(stroke
				(width 0.1)
				(type default)
			)
			(layer "B.Fab")
		)
		(fp_line
			(start 0.12065 0.3048)
			(end 0.67945 0.3048)
			(stroke
				(width 0.1)
				(type default)
			)
			(layer "B.Fab")
		)
		(fp_line
			(start 0.12065 0.2794)
			(end 0.12065 0.3048)
			(stroke
				(width 0.1)
				(type default)
			)
			(layer "B.Fab")
		)
		(fp_line
			(start 0.12065 -0.2794)
			(end -0.12065 -0.2794)
			(stroke
				(width 0.1)
				(type default)
			)
			(layer "B.Fab")
		)
		(fp_line
			(start 0.12065 -0.305054)
			(end 0.12065 -0.2794)
			(stroke
				(width 0.1)
				(type default)
			)
			(layer "B.Fab")
		)
		(fp_line
			(start -0.120396 0.3048)
			(end -0.120396 0.2794)
			(stroke
				(width 0.1)
				(type default)
			)
			(layer "B.Fab")
		)
		(fp_line
			(start -0.120396 0.2794)
			(end 0.12065 0.2794)
			(stroke
				(width 0.1)
				(type default)
			)
			(layer "B.Fab")
		)
		(fp_line
			(start -0.12065 -0.2794)
			(end -0.12065 -0.3048)
			(stroke
				(width 0.1)
				(type default)
			)
			(layer "B.Fab")
		)
		(fp_line
			(start -0.12065 -0.3048)
			(end -0.67945 -0.3048)
			(stroke
				(width 0.1)
				(type default)
			)
			(layer "B.Fab")
		)
		(fp_line
			(start -0.67945 0.3048)
			(end -0.120396 0.3048)
			(stroke
				(width 0.1)
				(type default)
			)
			(layer "B.Fab")
		)
		(fp_line
			(start -0.67945 -0.3048)
			(end -0.67945 0.3048)
			(stroke
				(width 0.1)
				(type default)
			)
			(layer "B.Fab")
		)
		(pad "1" smd circle
			(at 0.40005 0)
			(size 0 0)
			(layers "B.Cu" "B.Mask" "B.Paste")
			(net "PVDDCR_CPU0_P0")
		)
		(pad "2" smd circle
			(at -0.40005 0)
			(size 0 0)
			(layers "B.Cu" "B.Mask" "B.Paste")
			(net "GND")
		)
	)
)
